# T6G (Grand Teton) — schematic netlist excerpt (pin names and nets, part order shuffled) for the footprints in the layout excerpt that follows; sources: Cadence DE-HDL packaged netlist, KiCad conversion of 04192023_DAF0TMB3IC0_F0TG_MB_C_brd_V02_OCP.brd

R2927  Q_RES  100K 1% CHIP  pkg 0402LF  page 130 : A = RST_SWB_BIC_BUF_R_N ; B = GND
C2231  Q_CAP  22UF 4V 20% X6S  pkg C0402  page 69 : A = PVDDCR_CPU1_P0 ; B = GND

(kicad_pcb
	(version 20260206)
	(generator "pcbnew")
	(generator_version "10.0")
	(general
		(thickness 1.6)
		(legacy_teardrops no)
	)
	(paper "A4")
	(title_block
		(title "04192023_DAF0TMB3IC0_F0TG_MB_C_brd_V02_OCP.brd")
		(comment 1 "Grand Teton / footprints 6025-6026 of 8354")
	)
	(layers
		(0 "F.Cu" signal "TOP")
		(4 "In1.Cu" signal "GND")
		(6 "In2.Cu" signal "IN1")
		(8 "In3.Cu" signal "GND1")
		(10 "In4.Cu" signal "IN2")
		(12 "In5.Cu" signal "GND2")
		(14 "In6.Cu" signal "IN3")
		(16 "In7.Cu" signal "GND3")
		(18 "In8.Cu" signal "VCC")
		(20 "In9.Cu" signal "VCC1")
		(22 "In10.Cu" signal "GND4")
		(24 "In11.Cu" signal "IN4")
		(26 "In12.Cu" signal "GND5")
		(28 "In13.Cu" signal "IN5")
		(30 "In14.Cu" signal "GND6")
		(32 "In15.Cu" signal "IN6")
		(34 "In16.Cu" signal "GND7")
		(2 "B.Cu" signal "BOTTOM")
		(9 "F.Adhes" user "F.Adhesive")
		(11 "B.Adhes" user "B.Adhesive")
		(13 "F.Paste" user "Package Geometry/Pastemask Top")
		(15 "B.Paste" user "Package Geometry/Pastemask Bottom")
		(5 "F.SilkS" user "Ref Des/Silkscreen Top")
		(7 "B.SilkS" user "Ref Des/Silkscreen Bottom")
		(1 "F.Mask" user "Board Geometry/Soldermask Top")
		(3 "B.Mask" user "Board Geometry/Soldermask Bottom")
		(17 "Dwgs.User" user "User.Drawings")
		(19 "Cmts.User" user "User.Comments")
		(21 "Eco1.User" user "User.Eco1")
		(23 "Eco2.User" user "User.Eco2")
		(25 "Edge.Cuts" user "Board Geometry/Outline")
		(27 "Margin" user)
		(31 "F.CrtYd" user "Package Geometry/Place Bound Top")
		(29 "B.CrtYd" user "Package Geometry/Place Bound Bottom")
		(35 "F.Fab" user "Ref Des/Assembly Top")
		(33 "B.Fab" user "Ref Des/Assembly Bottom")
	)
	(footprint ""
		(layer "B.Cu")
		(at 348.818454 -267.52931)
		(property "Reference" "C2231"
			(at 0 0 0)
			(layer "B.SilkS")
			(hide yes)
			(effects
				(font
					(size 1.27 1.27)
				)
				(justify mirror)
			)
		)
		(property "Value" ""
			(at 0 0 0)
			(layer "B.Fab")
			(effects
				(font
					(size 1.27 1.27)
				)
				(justify mirror)
			)
		)
		(duplicate_pad_numbers_are_jumpers no)
		(fp_line
			(start -0.7874 -0.4064)
			(end -0.7874 0.4064)
			(stroke
				(width 0.1524)
				(type default)
			)
			(layer "B.SilkS")
		)
		(fp_line
			(start -0.7874 0.4064)
			(end 0.7874 0.4064)
			(stroke
				(width 0.1524)
				(type default)
			)
			(layer "B.SilkS")
		)
		(fp_line
			(start 0.7874 -0.4064)
			(end -0.7874 -0.4064)
			(stroke
				(width 0.1524)
				(type default)
			)
			(layer "B.SilkS")
		)
		(fp_line
			(start 0.7874 0.4064)
			(end 0.7874 -0.4064)
			(stroke
				(width 0.1524)
				(type default)
			)
			(layer "B.SilkS")
		)
		(fp_line
			(start -0.67945 -0.3048)
			(end -0.67945 0.3048)
			(stroke
				(width 0.1)
				(type default)
			)
			(layer "B.Fab")
		)
		(fp_line
			(start -0.67945 0.3048)
			(end -0.120396 0.3048)
			(stroke
				(width 0.1)
				(type default)
			)
			(layer "B.Fab")
		)
		(fp_line
			(start -0.12065 -0.3048)
			(end -0.67945 -0.3048)
			(stroke
				(width 0.1)
				(type default)
			)
			(layer "B.Fab")
		)
		(fp_line
			(start -0.12065 -0.2794)
			(end -0.12065 -0.3048)
			(stroke
				(width 0.1)
				(type default)
			)
			(layer "B.Fab")
		)
		(fp_line
			(start -0.120396 0.2794)
			(end 0.12065 0.2794)
			(stroke
				(width 0.1)
				(type default)
			)
			(layer "B.Fab")
		)
		(fp_line
			(start -0.120396 0.3048)
			(end -0.120396 0.2794)
			(stroke
				(width 0.1)
				(type default)
			)
			(layer "B.Fab")
		)
		(fp_line
			(start 0.12065 -0.305054)
			(end 0.12065 -0.2794)
			(stroke
				(width 0.1)
				(type default)
			)
			(layer "B.Fab")
		)
		(fp_line
			(start 0.12065 -0.2794)
			(end -0.12065 -0.2794)
			(stroke
				(width 0.1)
				(type default)
			)
			(layer "B.Fab")
		)
		(fp_line
			(start 0.12065 0.2794)
			(end 0.12065 0.3048)
			(stroke
				(width 0.1)
				(type default)
			)
			(layer "B.Fab")
		)
		(fp_line
			(start 0.12065 0.3048)
			(end 0.67945 0.3048)
			(stroke
				(width 0.1)
				(type default)
			)
			(layer "B.Fab")
		)
		(fp_line
			(start 0.67945 -0.305054)
			(end 0.12065 -0.305054)
			(stroke
				(width 0.1)
				(type default)
			)
			(layer "B.Fab")
		)
		(fp_line
			(start 0.67945 0.3048)
			(end 0.67945 -0.305054)
			(stroke
				(width 0.1)
				(type default)
			)
			(layer "B.Fab")
		)
		(pad "1" smd circle
			(at 0.40005 0 180)
			(size 0 0)
			(layers "B.Cu" "B.Mask" "B.Paste")
			(net "PVDDCR_CPU1_P0")
		)
		(pad "2" smd circle
			(at -0.40005 0 180)
			(size 0 0)
			(layers "B.Cu" "B.Mask" "B.Paste")
			(net "GND")
		)
	)
	(footprint ""
		(layer "B.Cu")
		(at 180.166518 -415.616644 90)
		(property "Reference" "R2927"
			(at 0 0 90)
			(layer "B.SilkS")
			(hide yes)
			(effects
				(font
					(size 1.27 1.27)
				)
				(justify mirror)
			)
		)
		(property "Value" ""
			(at 0 0 90)
			(layer "B.Fab")
			(effects
				(font
					(size 1.27 1.27)
				)
				(justify mirror)
			)
		)
		(duplicate_pad_numbers_are_jumpers no)
		(fp_line
			(start 0.7874 -0.4064)
			(end -0.7874 -0.4064)
			(stroke
				(width 0.1524)
				(type default)
			)
			(layer "B.SilkS")
		)
		(fp_line
			(start -0.7874 -0.4064)
			(end -0.7874 0.4064)
			(stroke
				(width 0.1524)
				(type default)
			)
			(layer "B.SilkS")
		)
		(fp_line
			(start 0.7874 0.4064)
			(end 0.7874 -0.4064)
			(stroke
				(width 0.1524)
				(type default)
			)
			(layer "B.SilkS")
		)
		(fp_line
			(start -0.7874 0.4064)
			(end 0.7874 0.4064)
			(stroke
				(width 0.1524)
				(type default)
			)
			(layer "B.SilkS")
		)
		(fp_line
			(start 0.67945 -0.305054)
			(end 0.12065 -0.305054)
			(stroke
				(width 0.1)
				(type default)
			)
			(layer "B.Fab")
		)
		(fp_line
			(start 0.12065 -0.305054)
			(end 0.12065 -0.2794)
			(stroke
				(width 0.1)
				(type default)
			)
			(layer "B.Fab")
		)
		(fp_line
			(start -0.12065 -0.3048)
			(end -0.67945 -0.3048)
			(stroke
				(width 0.1)
				(type default)
			)
			(layer "B.Fab")
		)
		(fp_line
			(start -0.67945 -0.3048)
			(end -0.67945 0.3048)
			(stroke
				(width 0.1)
				(type default)
			)
			(layer "B.Fab")
		)
		(fp_line
			(start 0.12065 -0.2794)
			(end -0.12065 -0.2794)
			(stroke
				(width 0.1)
				(type default)
			)
			(layer "B.Fab")
		)
		(fp_line
			(start -0.12065 -0.2794)
			(end -0.12065 -0.3048)
			(stroke
				(width 0.1)
				(type default)
			)
			(layer "B.Fab")
		)
		(fp_line
			(start 0.12065 0.2794)
			(end 0.12065 0.3048)
			(stroke
				(width 0.1)
				(type default)
			)
			(layer "B.Fab")
		)
		(fp_line
			(start -0.120396 0.2794)
			(end 0.12065 0.2794)
			(stroke
				(width 0.1)
				(type default)
			)
			(layer "B.Fab")
		)
		(fp_line
			(start 0.67945 0.3048)
			(end 0.67945 -0.305054)
			(stroke
				(width 0.1)
				(type default)
			)
			(layer "B.Fab")
		)
		(fp_line
			(start 0.12065 0.3048)
			(end 0.67945 0.3048)
			(stroke
				(width 0.1)
				(type default)
			)
			(layer "B.Fab")
		)
		(fp_line
			(start -0.120396 0.3048)
			(end -0.120396 0.2794)
			(stroke
				(width 0.1)
				(type default)
			)
			(layer "B.Fab")
		)
		(fp_line
			(start -0.67945 0.3048)
			(end -0.120396 0.3048)
			(stroke
				(width 0.1)
				(type default)
			)
			(layer "B.Fab")
		)
		(pad "1" smd circle
			(at 0.40005 0 270)
			(size 0 0)
			(layers "B.Cu" "B.Mask" "B.Paste")
			(net "RST_SWB_BIC_BUF_R_N")
		)
		(pad "2" smd circle
			(at -0.40005 0 270)
			(size 0 0)
			(layers "B.Cu" "B.Mask" "B.Paste")
			(net "GND")
		)
	)
)
